# T6G (Grand Teton) — schematic netlist excerpt (pin names and nets, part order shuffled) for the footprints in the layout excerpt that follows; sources: Cadence DE-HDL packaged netlist, KiCad conversion of 04192023_DAF0TMB3IC0_F0TG_MB_C_brd_V02_OCP.brd

R2801  Q_RES  0 5% EMPTY  pkg 0402LF  page 240 : A = SMB_FAN_3V3AUX_R_SDA ; B = SMB_FAN_3V3AUX_BUF_SDA
R1589  Q_RES  49.9 1% CHIP  pkg 0402LF  page 107 : A = I3C_SPD_DDRGL_CPU1_SCL ; B = I3C_SPD_DDRJ_CPU1_SCL

(kicad_pcb
	(version 20260206)
	(generator "pcbnew")
	(generator_version "10.0")
	(general
		(thickness 1.6)
		(legacy_teardrops no)
	)
	(paper "A4")
	(title_block
		(title "04192023_DAF0TMB3IC0_F0TG_MB_C_brd_V02_OCP.brd")
		(comment 1 "Grand Teton / footprints 7911-7912 of 8354")
	)
	(layers
		(0 "F.Cu" signal "TOP")
		(4 "In1.Cu" signal "GND")
		(6 "In2.Cu" signal "IN1")
		(8 "In3.Cu" signal "GND1")
		(10 "In4.Cu" signal "IN2")
		(12 "In5.Cu" signal "GND2")
		(14 "In6.Cu" signal "IN3")
		(16 "In7.Cu" signal "GND3")
		(18 "In8.Cu" signal "VCC")
		(20 "In9.Cu" signal "VCC1")
		(22 "In10.Cu" signal "GND4")
		(24 "In11.Cu" signal "IN4")
		(26 "In12.Cu" signal "GND5")
		(28 "In13.Cu" signal "IN5")
		(30 "In14.Cu" signal "GND6")
		(32 "In15.Cu" signal "IN6")
		(34 "In16.Cu" signal "GND7")
		(2 "B.Cu" signal "BOTTOM")
		(9 "F.Adhes" user "F.Adhesive")
		(11 "B.Adhes" user "B.Adhesive")
		(13 "F.Paste" user "Package Geometry/Pastemask Top")
		(15 "B.Paste" user "Package Geometry/Pastemask Bottom")
		(5 "F.SilkS" user "Ref Des/Silkscreen Top")
		(7 "B.SilkS" user "Ref Des/Silkscreen Bottom")
		(1 "F.Mask" user "Board Geometry/Soldermask Top")
		(3 "B.Mask" user "Board Geometry/Soldermask Bottom")
		(17 "Dwgs.User" user "User.Drawings")
		(19 "Cmts.User" user "User.Comments")
		(21 "Eco1.User" user "User.Eco1")
		(23 "Eco2.User" user "User.Eco2")
		(25 "Edge.Cuts" user "Board Geometry/Outline")
		(27 "Margin" user)
		(31 "F.CrtYd" user "Package Geometry/Place Bound Top")
		(29 "B.CrtYd" user "Package Geometry/Place Bound Bottom")
		(35 "F.Fab" user "Ref Des/Assembly Top")
		(33 "B.Fab" user "Ref Des/Assembly Bottom")
	)
	(footprint ""
		(layer "B.Cu")
		(at 190.404496 -194.8942 180)
		(property "Reference" "R1589"
			(at 0 0 0)
			(layer "B.SilkS")
			(hide yes)
			(effects
				(font
					(size 1.27 1.27)
				)
				(justify mirror)
			)
		)
		(property "Value" ""
			(at 0 0 0)
			(layer "B.Fab")
			(effects
				(font
					(size 1.27 1.27)
				)
				(justify mirror)
			)
		)
		(duplicate_pad_numbers_are_jumpers no)
		(fp_line
			(start 0.7874 0.4064)
			(end 0.7874 -0.4064)
			(stroke
				(width 0.1524)
				(type default)
			)
			(layer "B.SilkS")
		)
		(fp_line
			(start 0.7874 -0.4064)
			(end -0.7874 -0.4064)
			(stroke
				(width 0.1524)
				(type default)
			)
			(layer "B.SilkS")
		)
		(fp_line
			(start -0.7874 0.4064)
			(end 0.7874 0.4064)
			(stroke
				(width 0.1524)
				(type default)
			)
			(layer "B.SilkS")
		)
		(fp_line
			(start -0.7874 -0.4064)
			(end -0.7874 0.4064)
			(stroke
				(width 0.1524)
				(type default)
			)
			(layer "B.SilkS")
		)
		(fp_line
			(start 0.67945 0.3048)
			(end 0.67945 -0.305054)
			(stroke
				(width 0.1)
				(type default)
			)
			(layer "B.Fab")
		)
		(fp_line
			(start 0.67945 -0.305054)
			(end 0.12065 -0.305054)
			(stroke
				(width 0.1)
				(type default)
			)
			(layer "B.Fab")
		)
		(fp_line
			(start 0.12065 0.3048)
			(end 0.67945 0.3048)
			(stroke
				(width 0.1)
				(type default)
			)
			(layer "B.Fab")
		)
		(fp_line
			(start 0.12065 0.2794)
			(end 0.12065 0.3048)
			(stroke
				(width 0.1)
				(type default)
			)
			(layer "B.Fab")
		)
		(fp_line
			(start 0.12065 -0.2794)
			(end -0.12065 -0.2794)
			(stroke
				(width 0.1)
				(type default)
			)
			(layer "B.Fab")
		)
		(fp_line
			(start 0.12065 -0.305054)
			(end 0.12065 -0.2794)
			(stroke
				(width 0.1)
				(type default)
			)
			(layer "B.Fab")
		)
		(fp_line
			(start -0.120396 0.3048)
			(end -0.120396 0.2794)
			(stroke
				(width 0.1)
				(type default)
			)
			(layer "B.Fab")
		)
		(fp_line
			(start -0.120396 0.2794)
			(end 0.12065 0.2794)
			(stroke
				(width 0.1)
				(type default)
			)
			(layer "B.Fab")
		)
		(fp_line
			(start -0.12065 -0.2794)
			(end -0.12065 -0.3048)
			(stroke
				(width 0.1)
				(type default)
			)
			(layer "B.Fab")
		)
		(fp_line
			(start -0.12065 -0.3048)
			(end -0.67945 -0.3048)
			(stroke
				(width 0.1)
				(type default)
			)
			(layer "B.Fab")
		)
		(fp_line
			(start -0.67945 0.3048)
			(end -0.120396 0.3048)
			(stroke
				(width 0.1)
				(type default)
			)
			(layer "B.Fab")
		)
		(fp_line
			(start -0.67945 -0.3048)
			(end -0.67945 0.3048)
			(stroke
				(width 0.1)
				(type default)
			)
			(layer "B.Fab")
		)
		(pad "1" smd circle
			(at 0.40005 0)
			(size 0 0)
			(layers "B.Cu" "B.Mask" "B.Paste")
			(net "I3C_SPD_DDRGL_CPU1_SCL")
		)
		(pad "2" smd circle
			(at -0.40005 0)
			(size 0 0)
			(layers "B.Cu" "B.Mask" "B.Paste")
			(net "I3C_SPD_DDRJ_CPU1_SCL")
		)
	)
	(footprint ""
		(layer "B.Cu")
		(at 173.583092 -418.7571 -90)
		(property "Reference" "R2801"
			(at 0 0 90)
			(layer "B.SilkS")
			(hide yes)
			(effects
				(font
					(size 1.27 1.27)
				)
				(justify mirror)
			)
		)
		(property "Value" ""
			(at 0 0 90)
			(layer "B.Fab")
			(effects
				(font
					(size 1.27 1.27)
				)
				(justify mirror)
			)
		)
		(duplicate_pad_numbers_are_jumpers no)
		(fp_line
			(start -0.7874 0.4064)
			(end 0.7874 0.4064)
			(stroke
				(width 0.1524)
				(type default)
			)
			(layer "B.SilkS")
		)
		(fp_line
			(start 0.7874 0.4064)
			(end 0.7874 -0.4064)
			(stroke
				(width 0.1524)
				(type default)
			)
			(layer "B.SilkS")
		)
		(fp_line
			(start -0.7874 -0.4064)
			(end -0.7874 0.4064)
			(stroke
				(width 0.1524)
				(type default)
			)
			(layer "B.SilkS")
		)
		(fp_line
			(start 0.7874 -0.4064)
			(end -0.7874 -0.4064)
			(stroke
				(width 0.1524)
				(type default)
			)
			(layer "B.SilkS")
		)
		(fp_line
			(start -0.67945 0.3048)
			(end -0.120396 0.3048)
			(stroke
				(width 0.1)
				(type default)
			)
			(layer "B.Fab")
		)
		(fp_line
			(start -0.120396 0.3048)
			(end -0.120396 0.2794)
			(stroke
				(width 0.1)
				(type default)
			)
			(layer "B.Fab")
		)
		(fp_line
			(start 0.12065 0.3048)
			(end 0.67945 0.3048)
			(stroke
				(width 0.1)
				(type default)
			)
			(layer "B.Fab")
		)
		(fp_line
			(start 0.67945 0.3048)
			(end 0.67945 -0.305054)
			(stroke
				(width 0.1)
				(type default)
			)
			(layer "B.Fab")
		)
		(fp_line
			(start -0.120396 0.2794)
			(end 0.12065 0.2794)
			(stroke
				(width 0.1)
				(type default)
			)
			(layer "B.Fab")
		)
		(fp_line
			(start 0.12065 0.2794)
			(end 0.12065 0.3048)
			(stroke
				(width 0.1)
				(type default)
			)
			(layer "B.Fab")
		)
		(fp_line
			(start -0.12065 -0.2794)
			(end -0.12065 -0.3048)
			(stroke
				(width 0.1)
				(type default)
			)
			(layer "B.Fab")
		)
		(fp_line
			(start 0.12065 -0.2794)
			(end -0.12065 -0.2794)
			(stroke
				(width 0.1)
				(type default)
			)
			(layer "B.Fab")
		)
		(fp_line
			(start -0.67945 -0.3048)
			(end -0.67945 0.3048)
			(stroke
				(width 0.1)
				(type default)
			)
			(layer "B.Fab")
		)
		(fp_line
			(start -0.12065 -0.3048)
			(end -0.67945 -0.3048)
			(stroke
				(width 0.1)
				(type default)
			)
			(layer "B.Fab")
		)
		(fp_line
			(start 0.12065 -0.305054)
			(end 0.12065 -0.2794)
			(stroke
				(width 0.1)
				(type default)
			)
			(layer "B.Fab")
		)
		(fp_line
			(start 0.67945 -0.305054)
			(end 0.12065 -0.305054)
			(stroke
				(width 0.1)
				(type default)
			)
			(layer "B.Fab")
		)
		(pad "1" smd circle
			(at 0.40005 0 90)
			(size 0 0)
			(layers "B.Cu" "B.Mask" "B.Paste")
			(net "SMB_FAN_3V3AUX_R_SDA")
		)
		(pad "2" smd circle
			(at -0.40005 0 90)
			(size 0 0)
			(layers "B.Cu" "B.Mask" "B.Paste")
			(net "SMB_FAN_3V3AUX_BUF_SDA")
		)
	)
)
